# S9S_MB_2U (Grand Teton) — schematic netlist excerpt (pin names and nets, part order shuffled) for the footprints in the layout excerpt that follows; sources: Cadence DE-HDL packaged netlist, KiCad conversion of 03242023_DA0F0TMBIJ0_F0T_Motherboard_J_brd_V01_OCP.brd

R4263  Q_RES  240 1% EMPTY  pkg 0402LF  page 119 : A = PD_CPU0_BIST_ENABLE ; B = GND
R4161  Q_RES  100K 1% EMPTY  pkg 0402LF  page 145 : A = GPU_3V3IO_RSVD4 ; B = GND

(kicad_pcb
	(version 20260206)
	(generator "pcbnew")
	(generator_version "10.0")
	(general
		(thickness 1.6)
		(legacy_teardrops no)
	)
	(paper "A4")
	(title_block
		(title "03242023_DA0F0TMBIJ0_F0T_Motherboard_J_brd_V01_OCP.brd")
		(comment 1 "Grand Teton / footprints 3053-3054 of 6105")
	)
	(layers
		(0 "F.Cu" signal "TOP")
		(4 "In1.Cu" signal "GND")
		(6 "In2.Cu" signal "IN1")
		(8 "In3.Cu" signal "GND1")
		(10 "In4.Cu" signal "IN2")
		(12 "In5.Cu" signal "GND2")
		(14 "In6.Cu" signal "IN3")
		(16 "In7.Cu" signal "GND3")
		(18 "In8.Cu" signal "VCC")
		(20 "In9.Cu" signal "VCC1")
		(22 "In10.Cu" signal "GND4")
		(24 "In11.Cu" signal "IN4")
		(26 "In12.Cu" signal "GND5")
		(28 "In13.Cu" signal "IN5")
		(30 "In14.Cu" signal "GND6")
		(32 "In15.Cu" signal "IN6")
		(34 "In16.Cu" signal "GND7")
		(2 "B.Cu" signal "BOTTOM")
		(9 "F.Adhes" user "F.Adhesive")
		(11 "B.Adhes" user "B.Adhesive")
		(13 "F.Paste" user "Package Geometry/Pastemask Top")
		(15 "B.Paste" user "Package Geometry/Pastemask Bottom")
		(5 "F.SilkS" user "Ref Des/Silkscreen Top")
		(7 "B.SilkS" user "Ref Des/Silkscreen Bottom")
		(1 "F.Mask" user "Board Geometry/Soldermask Top")
		(3 "B.Mask" user "Board Geometry/Soldermask Bottom")
		(17 "Dwgs.User" user "User.Drawings")
		(19 "Cmts.User" user "User.Comments")
		(21 "Eco1.User" user "User.Eco1")
		(23 "Eco2.User" user "User.Eco2")
		(25 "Edge.Cuts" user "Board Geometry/Outline")
		(27 "Margin" user)
		(31 "F.CrtYd" user "Package Geometry/Place Bound Top")
		(29 "B.CrtYd" user "Package Geometry/Place Bound Bottom")
		(35 "F.Fab" user "Ref Des/Assembly Top")
		(33 "B.Fab" user "Ref Des/Assembly Bottom")
	)
	(footprint ""
		(layer "F.Cu")
		(at 328.913998 -190.74511 -90)
		(property "Reference" "R4263"
			(at 0 0 270)
			(layer "F.SilkS")
			(hide yes)
			(effects
				(font
					(size 1.27 1.27)
				)
			)
		)
		(property "Value" ""
			(at 0 0 270)
			(layer "F.Fab")
			(effects
				(font
					(size 1.27 1.27)
				)
			)
		)
		(duplicate_pad_numbers_are_jumpers no)
		(fp_line
			(start -0.7874 0.4064)
			(end -0.7874 -0.4064)
			(stroke
				(width 0.1524)
				(type default)
			)
			(layer "F.SilkS")
		)
		(fp_line
			(start 0.7874 0.4064)
			(end -0.7874 0.4064)
			(stroke
				(width 0.1524)
				(type default)
			)
			(layer "F.SilkS")
		)
		(fp_line
			(start -0.7874 -0.4064)
			(end 0.7874 -0.4064)
			(stroke
				(width 0.1524)
				(type default)
			)
			(layer "F.SilkS")
		)
		(fp_line
			(start 0.7874 -0.4064)
			(end 0.7874 0.4064)
			(stroke
				(width 0.1524)
				(type default)
			)
			(layer "F.SilkS")
		)
		(fp_line
			(start -0.67945 0.3048)
			(end -0.67945 -0.305054)
			(stroke
				(width 0.1)
				(type default)
			)
			(layer "F.Fab")
		)
		(fp_line
			(start -0.12065 0.3048)
			(end -0.67945 0.3048)
			(stroke
				(width 0.1)
				(type default)
			)
			(layer "F.Fab")
		)
		(fp_line
			(start 0.120396 0.3048)
			(end 0.120396 0.2794)
			(stroke
				(width 0.1)
				(type default)
			)
			(layer "F.Fab")
		)
		(fp_line
			(start 0.67945 0.3048)
			(end 0.120396 0.3048)
			(stroke
				(width 0.1)
				(type default)
			)
			(layer "F.Fab")
		)
		(fp_line
			(start -0.12065 0.2794)
			(end -0.12065 0.3048)
			(stroke
				(width 0.1)
				(type default)
			)
			(layer "F.Fab")
		)
		(fp_line
			(start 0.120396 0.2794)
			(end -0.12065 0.2794)
			(stroke
				(width 0.1)
				(type default)
			)
			(layer "F.Fab")
		)
		(fp_line
			(start -0.12065 -0.2794)
			(end 0.12065 -0.2794)
			(stroke
				(width 0.1)
				(type default)
			)
			(layer "F.Fab")
		)
		(fp_line
			(start 0.12065 -0.2794)
			(end 0.12065 -0.3048)
			(stroke
				(width 0.1)
				(type default)
			)
			(layer "F.Fab")
		)
		(fp_line
			(start 0.12065 -0.3048)
			(end 0.67945 -0.3048)
			(stroke
				(width 0.1)
				(type default)
			)
			(layer "F.Fab")
		)
		(fp_line
			(start 0.67945 -0.3048)
			(end 0.67945 0.3048)
			(stroke
				(width 0.1)
				(type default)
			)
			(layer "F.Fab")
		)
		(fp_line
			(start -0.67945 -0.305054)
			(end -0.12065 -0.305054)
			(stroke
				(width 0.1)
				(type default)
			)
			(layer "F.Fab")
		)
		(fp_line
			(start -0.12065 -0.305054)
			(end -0.12065 -0.2794)
			(stroke
				(width 0.1)
				(type default)
			)
			(layer "F.Fab")
		)
		(pad "1" smd circle
			(at -0.40005 0 270)
			(size 0 0)
			(layers "F.Cu" "F.Mask" "F.Paste")
			(net "PD_CPU0_BIST_ENABLE")
		)
		(pad "2" smd circle
			(at 0.40005 0 270)
			(size 0 0)
			(layers "F.Cu" "F.Mask" "F.Paste")
			(net "GND")
		)
	)
	(footprint ""
		(layer "F.Cu")
		(at 357.587042 -393.28725 180)
		(property "Reference" "R4161"
			(at 0 0 180)
			(layer "F.SilkS")
			(hide yes)
			(effects
				(font
					(size 1.27 1.27)
				)
			)
		)
		(property "Value" ""
			(at 0 0 180)
			(layer "F.Fab")
			(effects
				(font
					(size 1.27 1.27)
				)
			)
		)
		(duplicate_pad_numbers_are_jumpers no)
		(fp_line
			(start 0.7874 0.4064)
			(end -0.7874 0.4064)
			(stroke
				(width 0.1524)
				(type default)
			)
			(layer "F.SilkS")
		)
		(fp_line
			(start 0.7874 -0.4064)
			(end 0.7874 0.4064)
			(stroke
				(width 0.1524)
				(type default)
			)
			(layer "F.SilkS")
		)
		(fp_line
			(start -0.7874 0.4064)
			(end -0.7874 -0.4064)
			(stroke
				(width 0.1524)
				(type default)
			)
			(layer "F.SilkS")
		)
		(fp_line
			(start -0.7874 -0.4064)
			(end 0.7874 -0.4064)
			(stroke
				(width 0.1524)
				(type default)
			)
			(layer "F.SilkS")
		)
		(fp_line
			(start 0.67945 0.3048)
			(end 0.120396 0.3048)
			(stroke
				(width 0.1)
				(type default)
			)
			(layer "F.Fab")
		)
		(fp_line
			(start 0.67945 -0.3048)
			(end 0.67945 0.3048)
			(stroke
				(width 0.1)
				(type default)
			)
			(layer "F.Fab")
		)
		(fp_line
			(start 0.12065 -0.2794)
			(end 0.12065 -0.3048)
			(stroke
				(width 0.1)
				(type default)
			)
			(layer "F.Fab")
		)
		(fp_line
			(start 0.12065 -0.3048)
			(end 0.67945 -0.3048)
			(stroke
				(width 0.1)
				(type default)
			)
			(layer "F.Fab")
		)
		(fp_line
			(start 0.120396 0.3048)
			(end 0.120396 0.2794)
			(stroke
				(width 0.1)
				(type default)
			)
			(layer "F.Fab")
		)
		(fp_line
			(start 0.120396 0.2794)
			(end -0.12065 0.2794)
			(stroke
				(width 0.1)
				(type default)
			)
			(layer "F.Fab")
		)
		(fp_line
			(start -0.12065 0.3048)
			(end -0.67945 0.3048)
			(stroke
				(width 0.1)
				(type default)
			)
			(layer "F.Fab")
		)
		(fp_line
			(start -0.12065 0.2794)
			(end -0.12065 0.3048)
			(stroke
				(width 0.1)
				(type default)
			)
			(layer "F.Fab")
		)
		(fp_line
			(start -0.12065 -0.2794)
			(end 0.12065 -0.2794)
			(stroke
				(width 0.1)
				(type default)
			)
			(layer "F.Fab")
		)
		(fp_line
			(start -0.12065 -0.305054)
			(end -0.12065 -0.2794)
			(stroke
				(width 0.1)
				(type default)
			)
			(layer "F.Fab")
		)
		(fp_line
			(start -0.67945 0.3048)
			(end -0.67945 -0.305054)
			(stroke
				(width 0.1)
				(type default)
			)
			(layer "F.Fab")
		)
		(fp_line
			(start -0.67945 -0.305054)
			(end -0.12065 -0.305054)
			(stroke
				(width 0.1)
				(type default)
			)
			(layer "F.Fab")
		)
		(pad "1" smd circle
			(at -0.40005 0 180)
			(size 0 0)
			(layers "F.Cu" "F.Mask" "F.Paste")
			(net "GPU_3V3IO_RSVD4")
		)
		(pad "2" smd circle
			(at 0.40005 0 180)
			(size 0 0)
			(layers "F.Cu" "F.Mask" "F.Paste")
			(net "GND")
		)
	)
)
